# T6G (Grand Teton) — schematic netlist excerpt (pin names and nets, part order shuffled) for the footprints in the layout excerpt that follows; sources: Cadence DE-HDL packaged netlist, KiCad conversion of 04192023_DAF0TMB3IC0_F0TG_MB_C_brd_V02_OCP.brd

R868  Q_RES  4.7K 5% EMPTY  pkg 0201LF  page 342 : A = P1V8_CPU1_RT_1D ; B = RT_CPU1_P2_SCAN_MODE
PR397  Q_RES  0 5% CHIP  pkg 0402LF  page 226 : A = P3V3_AUX ; B = PVDD18_S5_P1_VCC

U6  PI3CSW12ZUAEX  IC  pkg UQFN10_0-5_2X1-5  page 161
  \1d+\  = SMB_CPU0_SEC_R_SCL
  \1d-\  = SMB_CPU0_SEC_R_SDA
  \2d+\  = SMB_CPU1_SEC_R_SCL
  \2d-\  = SMB_CPU1_SEC_R_SDA
  GND  = GND
  \oe#\  = FM_SEC_MUX_OE_N
  \d-\  = SMB_CPU0_CPU1_SEC_SDA_R2
  \d+\  = SMB_CPU0_CPU1_SEC_SCL_R2
  S  = FM_SEC_MUX_SEL
  VDD  = P3V3_AUX

(kicad_pcb
	(version 20260206)
	(generator "pcbnew")
	(generator_version "10.0")
	(general
		(thickness 1.6)
		(legacy_teardrops no)
	)
	(paper "A4")
	(title_block
		(title "04192023_DAF0TMB3IC0_F0TG_MB_C_brd_V02_OCP.brd")
		(comment 1 "Grand Teton / footprints 5327-5329 of 8354")
	)
	(layers
		(0 "F.Cu" signal "TOP")
		(4 "In1.Cu" signal "GND")
		(6 "In2.Cu" signal "IN1")
		(8 "In3.Cu" signal "GND1")
		(10 "In4.Cu" signal "IN2")
		(12 "In5.Cu" signal "GND2")
		(14 "In6.Cu" signal "IN3")
		(16 "In7.Cu" signal "GND3")
		(18 "In8.Cu" signal "VCC")
		(20 "In9.Cu" signal "VCC1")
		(22 "In10.Cu" signal "GND4")
		(24 "In11.Cu" signal "IN4")
		(26 "In12.Cu" signal "GND5")
		(28 "In13.Cu" signal "IN5")
		(30 "In14.Cu" signal "GND6")
		(32 "In15.Cu" signal "IN6")
		(34 "In16.Cu" signal "GND7")
		(2 "B.Cu" signal "BOTTOM")
		(9 "F.Adhes" user "F.Adhesive")
		(11 "B.Adhes" user "B.Adhesive")
		(13 "F.Paste" user "Package Geometry/Pastemask Top")
		(15 "B.Paste" user "Package Geometry/Pastemask Bottom")
		(5 "F.SilkS" user "Ref Des/Silkscreen Top")
		(7 "B.SilkS" user "Ref Des/Silkscreen Bottom")
		(1 "F.Mask" user "Board Geometry/Soldermask Top")
		(3 "B.Mask" user "Board Geometry/Soldermask Bottom")
		(17 "Dwgs.User" user "User.Drawings")
		(19 "Cmts.User" user "User.Comments")
		(21 "Eco1.User" user "User.Eco1")
		(23 "Eco2.User" user "User.Eco2")
		(25 "Edge.Cuts" user "Board Geometry/Outline")
		(27 "Margin" user)
		(31 "F.CrtYd" user "Package Geometry/Place Bound Top")
		(29 "B.CrtYd" user "Package Geometry/Place Bound Bottom")
		(35 "F.Fab" user "Ref Des/Assembly Top")
		(33 "B.Fab" user "Ref Des/Assembly Bottom")
	)
	(footprint ""
		(layer "B.Cu")
		(at 75.51801 -148.451316 -90)
		(property "Reference" "PR397"
			(at 0 0 90)
			(layer "B.SilkS")
			(hide yes)
			(effects
				(font
					(size 1.27 1.27)
				)
				(justify mirror)
			)
		)
		(property "Value" ""
			(at 0 0 90)
			(layer "B.Fab")
			(effects
				(font
					(size 1.27 1.27)
				)
				(justify mirror)
			)
		)
		(duplicate_pad_numbers_are_jumpers no)
		(fp_line
			(start -0.7874 0.4064)
			(end 0.7874 0.4064)
			(stroke
				(width 0.1524)
				(type default)
			)
			(layer "B.SilkS")
		)
		(fp_line
			(start 0.7874 0.4064)
			(end 0.7874 -0.4064)
			(stroke
				(width 0.1524)
				(type default)
			)
			(layer "B.SilkS")
		)
		(fp_line
			(start -0.7874 -0.4064)
			(end -0.7874 0.4064)
			(stroke
				(width 0.1524)
				(type default)
			)
			(layer "B.SilkS")
		)
		(fp_line
			(start 0.7874 -0.4064)
			(end -0.7874 -0.4064)
			(stroke
				(width 0.1524)
				(type default)
			)
			(layer "B.SilkS")
		)
		(fp_line
			(start -0.67945 0.3048)
			(end -0.120396 0.3048)
			(stroke
				(width 0.1)
				(type default)
			)
			(layer "B.Fab")
		)
		(fp_line
			(start -0.120396 0.3048)
			(end -0.120396 0.2794)
			(stroke
				(width 0.1)
				(type default)
			)
			(layer "B.Fab")
		)
		(fp_line
			(start 0.12065 0.3048)
			(end 0.67945 0.3048)
			(stroke
				(width 0.1)
				(type default)
			)
			(layer "B.Fab")
		)
		(fp_line
			(start 0.67945 0.3048)
			(end 0.67945 -0.305054)
			(stroke
				(width 0.1)
				(type default)
			)
			(layer "B.Fab")
		)
		(fp_line
			(start -0.120396 0.2794)
			(end 0.12065 0.2794)
			(stroke
				(width 0.1)
				(type default)
			)
			(layer "B.Fab")
		)
		(fp_line
			(start 0.12065 0.2794)
			(end 0.12065 0.3048)
			(stroke
				(width 0.1)
				(type default)
			)
			(layer "B.Fab")
		)
		(fp_line
			(start -0.12065 -0.2794)
			(end -0.12065 -0.3048)
			(stroke
				(width 0.1)
				(type default)
			)
			(layer "B.Fab")
		)
		(fp_line
			(start 0.12065 -0.2794)
			(end -0.12065 -0.2794)
			(stroke
				(width 0.1)
				(type default)
			)
			(layer "B.Fab")
		)
		(fp_line
			(start -0.67945 -0.3048)
			(end -0.67945 0.3048)
			(stroke
				(width 0.1)
				(type default)
			)
			(layer "B.Fab")
		)
		(fp_line
			(start -0.12065 -0.3048)
			(end -0.67945 -0.3048)
			(stroke
				(width 0.1)
				(type default)
			)
			(layer "B.Fab")
		)
		(fp_line
			(start 0.12065 -0.305054)
			(end 0.12065 -0.2794)
			(stroke
				(width 0.1)
				(type default)
			)
			(layer "B.Fab")
		)
		(fp_line
			(start 0.67945 -0.305054)
			(end 0.12065 -0.305054)
			(stroke
				(width 0.1)
				(type default)
			)
			(layer "B.Fab")
		)
		(pad "1" smd circle
			(at 0.40005 0 90)
			(size 0 0)
			(layers "B.Cu" "B.Mask" "B.Paste")
			(net "P3V3_AUX")
		)
		(pad "2" smd circle
			(at -0.40005 0 90)
			(size 0 0)
			(layers "B.Cu" "B.Mask" "B.Paste")
			(net "PVDD18_S5_P1_VCC")
		)
	)
	(footprint ""
		(layer "B.Cu")
		(at 141.623542 -383.7432 180)
		(property "Reference" "R868"
			(at 0 0 0)
			(layer "B.SilkS")
			(hide yes)
			(effects
				(font
					(size 1.27 1.27)
				)
				(justify mirror)
			)
		)
		(property "Value" ""
			(at 0 0 0)
			(layer "B.Fab")
			(effects
				(font
					(size 1.27 1.27)
				)
				(justify mirror)
			)
		)
		(duplicate_pad_numbers_are_jumpers no)
		(fp_line
			(start 0.32512 0.175006)
			(end 0.32512 -0.175006)
			(stroke
				(width 0.1)
				(type default)
			)
			(layer "B.Fab")
		)
		(fp_line
			(start 0.32512 -0.175006)
			(end -0.32512 -0.175006)
			(stroke
				(width 0.1)
				(type default)
			)
			(layer "B.Fab")
		)
		(fp_line
			(start -0.32512 0.175006)
			(end 0.32512 0.175006)
			(stroke
				(width 0.1)
				(type default)
			)
			(layer "B.Fab")
		)
		(fp_line
			(start -0.32512 -0.175006)
			(end -0.32512 0.175006)
			(stroke
				(width 0.1)
				(type default)
			)
			(layer "B.Fab")
		)
		(pad "1" smd rect
			(at 0.2667 0)
			(size 0.3048 0.381)
			(layers "B.Cu" "B.Mask" "B.Paste")
			(net "P1V8_CPU1_RT_1D")
		)
		(pad "2" smd rect
			(at -0.2667 0 180)
			(size 0.3048 0.381)
			(layers "B.Cu" "B.Mask" "B.Paste")
			(net "RT_CPU1_P2_SCAN_MODE")
		)
	)
	(footprint ""
		(layer "B.Cu")
		(at 238.669576 -237.230666 -90)
		(property "Reference" "U6"
			(at 0.09271 2.847594 270)
			(unlocked yes)
			(layer "B.SilkS")
			(effects
				(font
					(size 0.7874 0.5842)
					(thickness 0.1524)
				)
				(justify mirror)
			)
		)
		(property "Value" ""
			(at 0 0 90)
			(layer "B.Fab")
			(effects
				(font
					(size 1.27 1.27)
				)
				(justify mirror)
			)
		)
		(duplicate_pad_numbers_are_jumpers no)
		(fp_line
			(start -1.03378 1.284478)
			(end 1.03378 1.284478)
			(stroke
				(width 0.1524)
				(type default)
			)
			(layer "B.SilkS")
		)
		(fp_line
			(start 1.03378 1.284478)
			(end 1.03378 -1.284478)
			(stroke
				(width 0.1524)
				(type default)
			)
			(layer "B.SilkS")
		)
		(fp_line
			(start -1.03378 -1.284478)
			(end -1.03378 1.284478)
			(stroke
				(width 0.1524)
				(type default)
			)
			(layer "B.SilkS")
		)
		(fp_line
			(start 1.03378 -1.284478)
			(end -1.03378 -1.284478)
			(stroke
				(width 0.1524)
				(type default)
			)
			(layer "B.SilkS")
		)
		(fp_poly
			(pts
				(xy 1.485646 -1.824482) (xy 1.20015 -1.211326) (xy 1.86182 -1.350772)
			)
			(stroke
				(width 0)
				(type default)
			)
			(fill yes)
			(layer "B.SilkS")
		)
		(fp_line
			(start -0.774954 1.02489)
			(end 0.774954 1.02489)
			(stroke
				(width 0.1)
				(type default)
			)
			(layer "B.Fab")
		)
		(fp_line
			(start 0.774954 1.02489)
			(end 0.774954 -1.02489)
			(stroke
				(width 0.1)
				(type default)
			)
			(layer "B.Fab")
		)
		(fp_line
			(start -0.774954 -1.02489)
			(end -0.774954 1.02489)
			(stroke
				(width 0.1)
				(type default)
			)
			(layer "B.Fab")
		)
		(fp_line
			(start 0.774954 -1.02489)
			(end -0.774954 -1.02489)
			(stroke
				(width 0.1)
				(type default)
			)
			(layer "B.Fab")
		)
		(fp_poly
			(pts
				(xy 1.201674 -0.750062) (xy 1.806702 -0.447548) (xy 1.806702 -1.052576)
			)
			(stroke
				(width 0)
				(type default)
			)
			(fill yes)
			(layer "B.Fab")
		)
		(pad "1" smd rect
			(at 0.64008 -0.750062)
			(size 0.3048 0.5334)
			(layers "B.Cu" "B.Mask" "B.Paste")
			(net "SMB_CPU0_SEC_R_SCL")
		)
		(pad "2" smd rect
			(at 0.64008 -0.249936)
			(size 0.254 0.5334)
			(layers "B.Cu" "B.Mask" "B.Paste")
			(net "SMB_CPU0_SEC_R_SDA")
		)
		(pad "3" smd rect
			(at 0.64008 0.249936)
			(size 0.254 0.5334)
			(layers "B.Cu" "B.Mask" "B.Paste")
			(net "SMB_CPU1_SEC_R_SCL")
		)
		(pad "4" smd rect
			(at 0.64008 0.750062)
			(size 0.3048 0.5334)
			(layers "B.Cu" "B.Mask" "B.Paste")
			(net "SMB_CPU1_SEC_R_SDA")
		)
		(pad "5" smd rect
			(at 0 0.839978 90)
			(size 0.3302 0.635)
			(layers "B.Cu" "B.Mask" "B.Paste")
			(net "GND")
		)
		(pad "6" smd rect
			(at -0.64008 0.750062)
			(size 0.3048 0.5334)
			(layers "B.Cu" "B.Mask" "B.Paste")
			(net "FM_SEC_MUX_OE_N")
		)
		(pad "7" smd rect
			(at -0.64008 0.249936)
			(size 0.254 0.5334)
			(layers "B.Cu" "B.Mask" "B.Paste")
			(net "SMB_CPU0_CPU1_SEC_SDA_R2")
		)
		(pad "8" smd rect
			(at -0.64008 -0.249936)
			(size 0.254 0.5334)
			(layers "B.Cu" "B.Mask" "B.Paste")
			(net "SMB_CPU0_CPU1_SEC_SCL_R2")
		)
		(pad "9" smd rect
			(at -0.64008 -0.750062)
			(size 0.3048 0.5334)
			(layers "B.Cu" "B.Mask" "B.Paste")
			(net "FM_SEC_MUX_SEL")
		)
		(pad "10" smd rect
			(at 0 -0.839978 90)
			(size 0.3302 0.635)
			(layers "B.Cu" "B.Mask" "B.Paste")
			(net "P3V3_AUX")
		)
	)
)
